(kicad_pcb
	(version 20241229)
	(generator "pcbnew")
	(generator_version "9.0")
	(general
		(thickness 1.6642)
		(legacy_teardrops no)
	)
	(paper "A3")
	(title_block
		(title "PolarFire SoM")
		(date "2025-07-22")
		(rev "1.1.4")
		(company "Antmicro Ltd")
		(comment 1 "www.antmicro.com")
		(comment 9 "footprints 443-446 of 470")
	)
	(layers
		(0 "F.Cu" mixed)
		(4 "In1.Cu" power)
		(6 "In2.Cu" signal)
		(8 "In3.Cu" power)
		(10 "In4.Cu" signal)
		(12 "In5.Cu" power)
		(14 "In6.Cu" power)
		(16 "In7.Cu" signal)
		(18 "In8.Cu" power)
		(20 "In9.Cu" signal)
		(22 "In10.Cu" power)
		(24 "In11.Cu" signal)
		(26 "In12.Cu" signal)
		(2 "B.Cu" mixed)
		(9 "F.Adhes" user "F.Adhesive")
		(11 "B.Adhes" user "B.Adhesive")
		(13 "F.Paste" user)
		(15 "B.Paste" user)
		(5 "F.SilkS" user "F.Silkscreen")
		(7 "B.SilkS" user "B.Silkscreen")
		(1 "F.Mask" user)
		(3 "B.Mask" user)
		(17 "Dwgs.User" user "User.Drawings")
		(19 "Cmts.User" user "User.Comments")
		(21 "Eco1.User" user "User.Eco1")
		(23 "Eco2.User" user "User.Eco2")
		(25 "Edge.Cuts" user)
		(27 "Margin" user)
		(31 "F.CrtYd" user "F.Courtyard")
		(29 "B.CrtYd" user "B.Courtyard")
		(35 "F.Fab" user)
		(33 "B.Fab" user)
	)
	(footprint "antmicro-footprints:C_0402_1005Metric"
		(layer "B.Cu")
		(at 225.33 123.45 -90)
		(descr "Capacitor SMD 0402")
		(tags "capacitor SMD 0402")
		(property "Reference" "C19"
			(at -3 0.03 270)
			(layer "B.SilkS")
			(effects
				(font
					(size 0.7 0.7)
					(thickness 0.15)
				)
				(justify left bottom mirror)
			)
		)
		(property "Value" "C_100n_0402"
			(at -1.022927 -2.155213 90)
			(layer "B.Fab")
			(hide yes)
			(effects
				(font
					(size 0.7 0.7)
					(thickness 0.15)
				)
				(justify left bottom mirror)
			)
		)
		(property "Datasheet" "https://www.murata.com/products/productdetail?partno=GRM155R61H104KE14%23"
			(at 0 0 270)
			(layer "F.Fab")
			(hide yes)
			(effects
				(font
					(size 1.27 1.27)
					(thickness 0.15)
				)
			)
		)
		(property "Description" "SMD Multilayer Ceramic Capacitor, 0.1 µF, 50 V, 0402 [1005 Metric], ± 10%, X5R, GRM Series"
			(at 0 0 270)
			(layer "F.Fab")
			(hide yes)
			(effects
				(font
					(size 1.27 1.27)
					(thickness 0.15)
				)
			)
		)
		(property "Author" "Antmicro"
			(at 101.88 348.78 0)
			(layer "B.Fab")
			(hide yes)
			(effects
				(font
					(size 1 1)
					(thickness 0.15)
				)
				(justify mirror)
			)
		)
		(property "Dielectric" "X5R"
			(at 101.88 348.78 0)
			(layer "B.Fab")
			(hide yes)
			(effects
				(font
					(size 1 1)
					(thickness 0.15)
				)
				(justify mirror)
			)
		)
		(property "License" "Apache-2.0"
			(at 101.88 348.78 0)
			(layer "B.Fab")
			(hide yes)
			(effects
				(font
					(size 1 1)
					(thickness 0.15)
				)
				(justify mirror)
			)
		)
		(property "MPN" "GRM155R61H104KE14D"
			(at 101.88 348.78 0)
			(layer "B.Fab")
			(hide yes)
			(effects
				(font
					(size 1 1)
					(thickness 0.15)
				)
				(justify mirror)
			)
		)
		(property "Manufacturer" "Murata"
			(at 101.88 348.78 0)
			(layer "B.Fab")
			(hide yes)
			(effects
				(font
					(size 1 1)
					(thickness 0.15)
				)
				(justify mirror)
			)
		)
		(property "Public" ""
			(at 101.88 348.78 0)
			(layer "B.Fab")
			(hide yes)
			(effects
				(font
					(size 1 1)
					(thickness 0.15)
				)
				(justify mirror)
			)
		)
		(property "Val" "100n"
			(at 101.88 348.78 0)
			(layer "B.Fab")
			(hide yes)
			(effects
				(font
					(size 1 1)
					(thickness 0.15)
				)
				(justify mirror)
			)
		)
		(property "Voltage" "50V"
			(at 101.88 348.78 0)
			(layer "B.Fab")
			(hide yes)
			(effects
				(font
					(size 1 1)
					(thickness 0.15)
				)
				(justify mirror)
			)
		)
		(sheetname "/FPGA GPIO/")
		(sheetfile "fpga-gpio.kicad_sch")
		(attr smd)
		(fp_rect
			(start -0.925 0.47)
			(end 0.925 -0.47)
			(stroke
				(width 0.05)
				(type default)
			)
			(fill no)
			(layer "B.CrtYd")
		)
		(fp_line
			(start -0.494 0.25)
			(end 0.504 0.25)
			(stroke
				(width 0.15)
				(type solid)
			)
			(layer "B.Fab")
		)
		(fp_line
			(start 0.504 0.25)
			(end 0.504 -0.248)
			(stroke
				(width 0.15)
				(type solid)
			)
			(layer "B.Fab")
		)
		(fp_line
			(start -0.494 -0.248)
			(end -0.494 0.25)
			(stroke
				(width 0.15)
				(type solid)
			)
			(layer "B.Fab")
		)
		(fp_line
			(start 0.504 -0.248)
			(end -0.494 -0.248)
			(stroke
				(width 0.15)
				(type solid)
			)
			(layer "B.Fab")
		)
		(fp_text user "License: Apache-2.0"
			(at -0.939 -5.799 90)
			(layer "B.Fab")
			(effects
				(font
					(size 0.7 0.7)
					(thickness 0.15)
				)
				(justify left bottom mirror)
			)
		)
		(fp_text user "Author: Antmicro"
			(at -0.939 -3.399 90)
			(layer "B.Fab")
			(effects
				(font
					(size 0.7 0.7)
					(thickness 0.15)
				)
				(justify left bottom mirror)
			)
		)
		(fp_text user "${REFERENCE}"
			(at -0.939 -4.599 90)
			(layer "B.Fab")
			(effects
				(font
					(size 0.7 0.7)
					(thickness 0.15)
				)
				(justify left bottom mirror)
			)
		)
		(pad "1" smd roundrect
			(at -0.48 0 270)
			(size 0.59 0.64)
			(layers "B.Cu" "B.Mask" "B.Paste")
			(roundrect_rratio 0.25)
			(net 50 "+3V3")
			(pintype "passive")
		)
		(pad "2" smd roundrect
			(at 0.48 0 270)
			(size 0.59 0.64)
			(layers "B.Cu" "B.Mask" "B.Paste")
			(roundrect_rratio 0.25)
			(net 417 "GND")
			(pintype "passive")
		)
	)
	(footprint "antmicro-footprints:C_0402_1005Metric"
		(layer "B.Cu")
		(at 184.8045 123.8755 -90)
		(descr "Capacitor SMD 0402")
		(tags "capacitor SMD 0402")
		(property "Reference" "C147"
			(at -1.2005 0.4795 270)
			(layer "B.SilkS")
			(effects
				(font
					(size 0.7 0.7)
					(thickness 0.15)
				)
				(justify left bottom mirror)
			)
		)
		(property "Value" "C_1u_0402"
			(at -1.022927 -2.155213 90)
			(layer "B.Fab")
			(hide yes)
			(effects
				(font
					(size 0.7 0.7)
					(thickness 0.15)
				)
				(justify left bottom mirror)
			)
		)
		(property "Datasheet" "https://product.tdk.com/en/search/capacitor/ceramic/mlcc/info?part_no=C1005X6S1A105K050BC"
			(at 0 0 270)
			(layer "F.Fab")
			(hide yes)
			(effects
				(font
					(size 1.27 1.27)
					(thickness 0.15)
				)
			)
		)
		(property "Description" "SMD Multilayer Ceramic Capacitor, 1 µF, 10 V, 0402 [1005 Metric], ± 10%, X6S, C"
			(at 0 0 270)
			(layer "F.Fab")
			(hide yes)
			(effects
				(font
					(size 1.27 1.27)
					(thickness 0.15)
				)
			)
		)
		(property "Author" "Antmicro"
			(at 60.929 308.68 0)
			(layer "B.Fab")
			(hide yes)
			(effects
				(font
					(size 1 1)
					(thickness 0.15)
				)
				(justify mirror)
			)
		)
		(property "Dielectric" "X5R"
			(at 60.929 308.68 0)
			(layer "B.Fab")
			(hide yes)
			(effects
				(font
					(size 1 1)
					(thickness 0.15)
				)
				(justify mirror)
			)
		)
		(property "License" "Apache-2.0"
			(at 60.929 308.68 0)
			(layer "B.Fab")
			(hide yes)
			(effects
				(font
					(size 1 1)
					(thickness 0.15)
				)
				(justify mirror)
			)
		)
		(property "MPN" "C1005X6S1A105K050BC"
			(at 60.929 308.68 0)
			(layer "B.Fab")
			(hide yes)
			(effects
				(font
					(size 1 1)
					(thickness 0.15)
				)
				(justify mirror)
			)
		)
		(property "Manufacturer" "TDK"
			(at 60.929 308.68 0)
			(layer "B.Fab")
			(hide yes)
			(effects
				(font
					(size 1 1)
					(thickness 0.15)
				)
				(justify mirror)
			)
		)
		(property "Public" ""
			(at 60.929 308.68 0)
			(layer "B.Fab")
			(hide yes)
			(effects
				(font
					(size 1 1)
					(thickness 0.15)
				)
				(justify mirror)
			)
		)
		(property "Val" "1u"
			(at 60.929 308.68 0)
			(layer "B.Fab")
			(hide yes)
			(effects
				(font
					(size 1 1)
					(thickness 0.15)
				)
				(justify mirror)
			)
		)
		(property "Voltage" "16V"
			(at 60.929 308.68 0)
			(layer "B.Fab")
			(hide yes)
			(effects
				(font
					(size 1 1)
					(thickness 0.15)
				)
				(justify mirror)
			)
		)
		(sheetname "/LPDDR4/")
		(sheetfile "lpddr.kicad_sch")
		(attr smd)
		(fp_rect
			(start -0.925 0.47)
			(end 0.925 -0.47)
			(stroke
				(width 0.05)
				(type default)
			)
			(fill no)
			(layer "B.CrtYd")
		)
		(fp_line
			(start -0.494 0.25)
			(end 0.504 0.25)
			(stroke
				(width 0.15)
				(type solid)
			)
			(layer "B.Fab")
		)
		(fp_line
			(start 0.504 0.25)
			(end 0.504 -0.248)
			(stroke
				(width 0.15)
				(type solid)
			)
			(layer "B.Fab")
		)
		(fp_line
			(start -0.494 -0.248)
			(end -0.494 0.25)
			(stroke
				(width 0.15)
				(type solid)
			)
			(layer "B.Fab")
		)
		(fp_line
			(start 0.504 -0.248)
			(end -0.494 -0.248)
			(stroke
				(width 0.15)
				(type solid)
			)
			(layer "B.Fab")
		)
		(fp_text user "License: Apache-2.0"
			(at -0.939 -5.799 90)
			(layer "B.Fab")
			(effects
				(font
					(size 0.7 0.7)
					(thickness 0.15)
				)
				(justify left bottom mirror)
			)
		)
		(fp_text user "${REFERENCE}"
			(at -0.939 -4.599 90)
			(layer "B.Fab")
			(effects
				(font
					(size 0.7 0.7)
					(thickness 0.15)
				)
				(justify left bottom mirror)
			)
		)
		(fp_text user "Author: Antmicro"
			(at -0.939 -3.399 90)
			(layer "B.Fab")
			(effects
				(font
					(size 0.7 0.7)
					(thickness 0.15)
				)
				(justify left bottom mirror)
			)
		)
		(pad "1" smd roundrect
			(at -0.48 0 270)
			(size 0.59 0.64)
			(layers "B.Cu" "B.Mask" "B.Paste")
			(roundrect_rratio 0.25)
			(net 417 "GND")
			(pintype "passive")
		)
		(pad "2" smd roundrect
			(at 0.48 0 270)
			(size 0.59 0.64)
			(layers "B.Cu" "B.Mask" "B.Paste")
			(roundrect_rratio 0.25)
			(net 2 "+1V1")
			(pintype "passive")
		)
	)
	(footprint "antmicro-footprints:C_0402_1005Metric"
		(layer "B.Cu")
		(at 177.7 134.1 90)
		(descr "Capacitor SMD 0402")
		(tags "capacitor SMD 0402")
		(property "Reference" "C135"
			(at -1.34 1.44 90)
			(layer "B.SilkS")
			(effects
				(font
					(size 0.7 0.7)
					(thickness 0.15)
				)
				(justify right bottom mirror)
			)
		)
		(property "Value" "C_1u_0402"
			(at -1.022927 -2.155213 90)
			(layer "B.Fab")
			(hide yes)
			(effects
				(font
					(size 0.7 0.7)
					(thickness 0.15)
				)
				(justify right bottom mirror)
			)
		)
		(property "Datasheet" "https://product.tdk.com/en/search/capacitor/ceramic/mlcc/info?part_no=C1005X6S1A105K050BC"
			(at 0 0 90)
			(layer "F.Fab")
			(hide yes)
			(effects
				(font
					(size 1.27 1.27)
					(thickness 0.15)
				)
			)
		)
		(property "Description" "SMD Multilayer Ceramic Capacitor, 1 µF, 10 V, 0402 [1005 Metric], ± 10%, X6S, C"
			(at 0 0 90)
			(layer "F.Fab")
			(hide yes)
			(effects
				(font
					(size 1.27 1.27)
					(thickness 0.15)
				)
			)
		)
		(property "Author" "Antmicro"
			(at 311.8 -43.6 0)
			(layer "B.Fab")
			(hide yes)
			(effects
				(font
					(size 1 1)
					(thickness 0.15)
				)
				(justify mirror)
			)
		)
		(property "Dielectric" "X5R"
			(at 311.8 -43.6 0)
			(layer "B.Fab")
			(hide yes)
			(effects
				(font
					(size 1 1)
					(thickness 0.15)
				)
				(justify mirror)
			)
		)
		(property "License" "Apache-2.0"
			(at 311.8 -43.6 0)
			(layer "B.Fab")
			(hide yes)
			(effects
				(font
					(size 1 1)
					(thickness 0.15)
				)
				(justify mirror)
			)
		)
		(property "MPN" "C1005X6S1A105K050BC"
			(at 311.8 -43.6 0)
			(layer "B.Fab")
			(hide yes)
			(effects
				(font
					(size 1 1)
					(thickness 0.15)
				)
				(justify mirror)
			)
		)
		(property "Manufacturer" "TDK"
			(at 311.8 -43.6 0)
			(layer "B.Fab")
			(hide yes)
			(effects
				(font
					(size 1 1)
					(thickness 0.15)
				)
				(justify mirror)
			)
		)
		(property "Public" ""
			(at 311.8 -43.6 0)
			(layer "B.Fab")
			(hide yes)
			(effects
				(font
					(size 1 1)
					(thickness 0.15)
				)
				(justify mirror)
			)
		)
		(property "Val" "1u"
			(at 311.8 -43.6 0)
			(layer "B.Fab")
			(hide yes)
			(effects
				(font
					(size 1 1)
					(thickness 0.15)
				)
				(justify mirror)
			)
		)
		(property "Voltage" "16V"
			(at 311.8 -43.6 0)
			(layer "B.Fab")
			(hide yes)
			(effects
				(font
					(size 1 1)
					(thickness 0.15)
				)
				(justify mirror)
			)
		)
		(sheetname "/LPDDR4/")
		(sheetfile "lpddr.kicad_sch")
		(attr smd)
		(fp_rect
			(start -0.925 0.47)
			(end 0.925 -0.47)
			(stroke
				(width 0.05)
				(type default)
			)
			(fill no)
			(layer "B.CrtYd")
		)
		(fp_line
			(start 0.504 -0.248)
			(end -0.494 -0.248)
			(stroke
				(width 0.15)
				(type solid)
			)
			(layer "B.Fab")
		)
		(fp_line
			(start -0.494 -0.248)
			(end -0.494 0.25)
			(stroke
				(width 0.15)
				(type solid)
			)
			(layer "B.Fab")
		)
		(fp_line
			(start 0.504 0.25)
			(end 0.504 -0.248)
			(stroke
				(width 0.15)
				(type solid)
			)
			(layer "B.Fab")
		)
		(fp_line
			(start -0.494 0.25)
			(end 0.504 0.25)
			(stroke
				(width 0.15)
				(type solid)
			)
			(layer "B.Fab")
		)
		(fp_text user "Author: Antmicro"
			(at -0.939 -3.399 270)
			(layer "B.Fab")
			(effects
				(font
					(size 0.7 0.7)
					(thickness 0.15)
				)
				(justify left bottom mirror)
			)
		)
		(fp_text user "${REFERENCE}"
			(at -0.939 -4.599 270)
			(layer "B.Fab")
			(effects
				(font
					(size 0.7 0.7)
					(thickness 0.15)
				)
				(justify left bottom mirror)
			)
		)
		(fp_text user "License: Apache-2.0"
			(at -0.939 -5.799 270)
			(layer "B.Fab")
			(effects
				(font
					(size 0.7 0.7)
					(thickness 0.15)
				)
				(justify left bottom mirror)
			)
		)
		(pad "1" smd roundrect
			(at -0.48 0 90)
			(size 0.59 0.64)
			(layers "B.Cu" "B.Mask" "B.Paste")
			(roundrect_rratio 0.25)
			(net 417 "GND")
			(pintype "passive")
		)
		(pad "2" smd roundrect
			(at 0.48 0 90)
			(size 0.59 0.64)
			(layers "B.Cu" "B.Mask" "B.Paste")
			(roundrect_rratio 0.25)
			(net 2 "+1V1")
			(pintype "passive")
		)
	)
	(footprint "antmicro-footprints:C_0402_1005Metric"
		(layer "B.Cu")
		(at 199.91 136.684 -90)
		(descr "Capacitor SMD 0402")
		(tags "capacitor SMD 0402")
		(property "Reference" "C34"
			(at -7.334 9.635 90)
			(layer "B.SilkS")
			(effects
				(font
					(size 0.7 0.7)
					(thickness 0.15)
				)
				(justify left bottom mirror)
			)
		)
		(property "Value" "C_10n_0402"
			(at -1.022927 -2.155213 90)
			(layer "B.Fab")
			(hide yes)
			(effects
				(font
					(size 0.7 0.7)
					(thickness 0.15)
				)
				(justify left bottom mirror)
			)
		)
		(property "Datasheet" "https://www.murata.com/products/productdetail?partno=GRM155R71H103KA88%23"
			(at 0 0 270)
			(layer "F.Fab")
			(hide yes)
			(effects
				(font
					(size 1.27 1.27)
					(thickness 0.15)
				)
			)
		)
		(property "Description" "SMD Multilayer Ceramic Capacitor, 10000 pF, 50 V, 0402 [1005 Metric], ± 10%, X7R, GRM Series"
			(at 0 0 270)
			(layer "F.Fab")
			(hide yes)
			(effects
				(font
					(size 1.27 1.27)
					(thickness 0.15)
				)
			)
		)
		(property "Author" "Antmicro"
			(at 63.226 336.594 0)
			(layer "B.Fab")
			(hide yes)
			(effects
				(font
					(size 1 1)
					(thickness 0.15)
				)
				(justify mirror)
			)
		)
		(property "Dielectric" "X7R"
			(at 63.226 336.594 0)
			(layer "B.Fab")
			(hide yes)
			(effects
				(font
					(size 1 1)
					(thickness 0.15)
				)
				(justify mirror)
			)
		)
		(property "License" "Apache-2.0"
			(at 63.226 336.594 0)
			(layer "B.Fab")
			(hide yes)
			(effects
				(font
					(size 1 1)
					(thickness 0.15)
				)
				(justify mirror)
			)
		)
		(property "MPN" "GRM155R71H103KA88D"
			(at 63.226 336.594 0)
			(layer "B.Fab")
			(hide yes)
			(effects
				(font
					(size 1 1)
					(thickness 0.15)
				)
				(justify mirror)
			)
		)
		(property "Manufacturer" "Murata"
			(at 63.226 336.594 0)
			(layer "B.Fab")
			(hide yes)
			(effects
				(font
					(size 1 1)
					(thickness 0.15)
				)
				(justify mirror)
			)
		)
		(property "Public" ""
			(at 63.226 336.594 0)
			(layer "B.Fab")
			(hide yes)
			(effects
				(font
					(size 1 1)
					(thickness 0.15)
				)
				(justify mirror)
			)
		)
		(property "Val" "10n"
			(at 63.226 336.594 0)
			(layer "B.Fab")
			(hide yes)
			(effects
				(font
					(size 1 1)
					(thickness 0.15)
				)
				(justify mirror)
			)
		)
		(property "Voltage" "50V"
			(at 63.226 336.594 0)
			(layer "B.Fab")
			(hide yes)
			(effects
				(font
					(size 1 1)
					(thickness 0.15)
				)
				(justify mirror)
			)
		)
		(sheetname "/FPGA Supply/")
		(sheetfile "fpga-supply.kicad_sch")
		(attr smd)
		(fp_rect
			(start -0.925 0.47)
			(end 0.925 -0.47)
			(stroke
				(width 0.05)
				(type default)
			)
			(fill no)
			(layer "B.CrtYd")
		)
		(fp_line
			(start -0.494 0.25)
			(end 0.504 0.25)
			(stroke
				(width 0.15)
				(type solid)
			)
			(layer "B.Fab")
		)
		(fp_line
			(start 0.504 0.25)
			(end 0.504 -0.248)
			(stroke
				(width 0.15)
				(type solid)
			)
			(layer "B.Fab")
		)
		(fp_line
			(start -0.494 -0.248)
			(end -0.494 0.25)
			(stroke
				(width 0.15)
				(type solid)
			)
			(layer "B.Fab")
		)
		(fp_line
			(start 0.504 -0.248)
			(end -0.494 -0.248)
			(stroke
				(width 0.15)
				(type solid)
			)
			(layer "B.Fab")
		)
		(fp_text user "License: Apache-2.0"
			(at -0.939 -5.799 90)
			(layer "B.Fab")
			(effects
				(font
					(size 0.7 0.7)
					(thickness 0.15)
				)
				(justify left bottom mirror)
			)
		)
		(fp_text user "${REFERENCE}"
			(at -0.939 -4.599 90)
			(layer "B.Fab")
			(effects
				(font
					(size 0.7 0.7)
					(thickness 0.15)
				)
				(justify left bottom mirror)
			)
		)
		(fp_text user "Author: Antmicro"
			(at -0.939 -3.399 90)
			(layer "B.Fab")
			(effects
				(font
					(size 0.7 0.7)
					(thickness 0.15)
				)
				(justify left bottom mirror)
			)
		)
		(pad "1" smd roundrect
			(at -0.48 0 270)
			(size 0.59 0.64)
			(layers "B.Cu" "B.Mask" "B.Paste")
			(roundrect_rratio 0.25)
			(net 417 "GND")
			(pintype "passive")
		)
		(pad "2" smd roundrect
			(at 0.48 0 270)
			(size 0.59 0.64)
			(layers "B.Cu" "B.Mask" "B.Paste")
			(roundrect_rratio 0.25)
			(net 418 "+2V5")
			(pintype "passive")
		)
	)
)
